(kicad_pcb
	(version 20260206)
	(generator "pcbnew")
	(generator_version "10.0")
	(general
		(thickness 1.6)
		(legacy_teardrops no)
	)
	(paper "A4")
	(title_block
		(title "01162023_DA0F0TEBIF0_F0T_Expander_BD_F_brd_V02_OCP.brd")
		(comment 1 "Grand Teton / footprints 8507-8512 of 9728")
	)
	(layers
		(0 "F.Cu" signal "TOP")
		(4 "In1.Cu" signal "GND")
		(6 "In2.Cu" signal "VCC")
		(8 "In3.Cu" signal "VCC1")
		(10 "In4.Cu" signal "GND1")
		(12 "In5.Cu" signal "IN1")
		(14 "In6.Cu" signal "GND2")
		(16 "In7.Cu" signal "IN2")
		(18 "In8.Cu" signal "GND3")
		(20 "In9.Cu" signal "IN3")
		(22 "In10.Cu" signal "GND4")
		(24 "In11.Cu" signal "IN4")
		(26 "In12.Cu" signal "GND5")
		(28 "In13.Cu" signal "IN5")
		(30 "In14.Cu" signal "GND6")
		(32 "In15.Cu" signal "IN6")
		(34 "In16.Cu" signal "GND7")
		(2 "B.Cu" signal "BOTTOM")
		(9 "F.Adhes" user "F.Adhesive")
		(11 "B.Adhes" user "B.Adhesive")
		(13 "F.Paste" user "Package Geometry/Pastemask Top")
		(15 "B.Paste" user "Package Geometry/Pastemask Bottom")
		(5 "F.SilkS" user "Ref Des/Silkscreen Top")
		(7 "B.SilkS" user "Ref Des/Silkscreen Bottom")
		(1 "F.Mask" user "Board Geometry/Soldermask Top")
		(3 "B.Mask" user "Board Geometry/Soldermask Bottom")
		(17 "Dwgs.User" user "User.Drawings")
		(19 "Cmts.User" user "User.Comments")
		(21 "Eco1.User" user "User.Eco1")
		(23 "Eco2.User" user "User.Eco2")
		(25 "Edge.Cuts" user "Board Geometry/Outline")
		(27 "Margin" user)
		(31 "F.CrtYd" user "Package Geometry/Place Bound Top")
		(29 "B.CrtYd" user "Package Geometry/Place Bound Bottom")
		(35 "F.Fab" user "Ref Des/Assembly Top")
		(33 "B.Fab" user "Ref Des/Assembly Bottom")
	)
	(footprint ""
		(layer "B.Cu")
		(at 400.369024 10.689844 180)
		(property "Reference" "DE15T_3"
			(at -2.627376 -3.383026 0)
			(unlocked yes)
			(layer "B.SilkS")
			(effects
				(font
					(size 0.7874 0.5842)
					(thickness 0.1524)
				)
				(justify left mirror)
			)
		)
		(property "Value" ""
			(at 0 0 0)
			(layer "B.Fab")
			(effects
				(font
					(size 1.27 1.27)
				)
				(justify mirror)
			)
		)
		(duplicate_pad_numbers_are_jumpers no)
		(fp_line
			(start 1.2192 2.1082)
			(end 1.2192 -2.1082)
			(stroke
				(width 0.1524)
				(type default)
			)
			(layer "B.SilkS")
		)
		(fp_line
			(start 1.2192 -2.1082)
			(end -1.2192 -2.1082)
			(stroke
				(width 0.1524)
				(type default)
			)
			(layer "B.SilkS")
		)
		(fp_line
			(start -1.2192 2.1082)
			(end 1.2192 2.1082)
			(stroke
				(width 0.1524)
				(type default)
			)
			(layer "B.SilkS")
		)
		(fp_line
			(start -1.2192 -2.1082)
			(end -1.2192 2.1082)
			(stroke
				(width 0.1524)
				(type default)
			)
			(layer "B.SilkS")
		)
		(pad "" np_thru_hole circle
			(at -3.4671 -1.27 90)
			(size 1.0414 1.0414)
			(drill 1.0414)
			(layers "*.Cu" "*.Mask")
			(clearance 0.381)
			(thermal_gap 0.381)
		)
		(pad "" np_thru_hole circle
			(at -3.4671 1.27 90)
			(size 1.0414 1.0414)
			(drill 1.0414)
			(layers "*.Cu" "*.Mask")
			(clearance 0.381)
			(thermal_gap 0.381)
		)
		(pad "" np_thru_hole circle
			(at 2.8829 -1.27 90)
			(size 1.0414 1.0414)
			(drill 1.0414)
			(layers "*.Cu" "*.Mask")
			(clearance 0.381)
			(thermal_gap 0.381)
		)
		(pad "" np_thru_hole circle
			(at 2.8829 1.27 90)
			(size 1.0414 1.0414)
			(drill 1.0414)
			(layers "*.Cu" "*.Mask")
			(clearance 0.381)
			(thermal_gap 0.381)
		)
		(pad "1" smd rect
			(at -0.8255 -0.249936 90)
			(size 0.3048 0.508)
			(layers "B.Cu" "B.Mask" "B.Paste")
			(net "85_10INCH_IN5_DP")
		)
		(pad "2" smd rect
			(at -0.8255 0.249936 90)
			(size 0.3048 0.508)
			(layers "B.Cu" "B.Mask" "B.Paste")
			(net "85_10INCH_IN5_DN")
		)
		(pad "3" smd circle
			(at 0 0)
			(size 0 0)
			(layers "B.Cu" "B.Mask" "B.Paste")
			(net "COUPON_GND2")
		)
		(zone
			(layers "F.Cu" "B.Cu" "In1.Cu" "In2.Cu" "In3.Cu" "In4.Cu" "In5.Cu" "In6.Cu"
				"In7.Cu" "In8.Cu" "In9.Cu" "In10.Cu" "In11.Cu" "In12.Cu" "In13.Cu" "In14.Cu"
				"In15.Cu" "In16.Cu"
			)
			(hatch none 0.5)
			(connect_pads
				(clearance 0)
			)
			(min_thickness 0.25)
			(keepout
				(tracks not_allowed)
				(vias allowed)
				(pads allowed)
				(copperpour not_allowed)
				(footprints allowed)
			)
			(placement
				(enabled no)
				(sheetname "")
			)
			(fill
				(thermal_gap 0.5)
				(thermal_bridge_width 0.5)
				(island_removal_mode 0)
			)
			(polygon
				(pts
					(arc
						(start 398.413224 9.419844)
						(mid 396.559024 9.419844)
						(end 398.413224 9.419844)
					)
				)
			)
		)
		(zone
			(layers "F.Cu" "B.Cu" "In1.Cu" "In2.Cu" "In3.Cu" "In4.Cu" "In5.Cu" "In6.Cu"
				"In7.Cu" "In8.Cu" "In9.Cu" "In10.Cu" "In11.Cu" "In12.Cu" "In13.Cu" "In14.Cu"
				"In15.Cu" "In16.Cu"
			)
			(hatch none 0.5)
			(connect_pads
				(clearance 0)
			)
			(min_thickness 0.25)
			(keepout
				(tracks not_allowed)
				(vias allowed)
				(pads allowed)
				(copperpour not_allowed)
				(footprints allowed)
			)
			(placement
				(enabled no)
				(sheetname "")
			)
			(fill
				(thermal_gap 0.5)
				(thermal_bridge_width 0.5)
				(island_removal_mode 0)
			)
			(polygon
				(pts
					(arc
						(start 398.413224 11.959844)
						(mid 396.559024 11.959844)
						(end 398.413224 11.959844)
					)
				)
			)
		)
		(zone
			(layers "F.Cu" "B.Cu" "In1.Cu" "In2.Cu" "In3.Cu" "In4.Cu" "In5.Cu" "In6.Cu"
				"In7.Cu" "In8.Cu" "In9.Cu" "In10.Cu" "In11.Cu" "In12.Cu" "In13.Cu" "In14.Cu"
				"In15.Cu" "In16.Cu"
			)
			(hatch none 0.5)
			(connect_pads
				(clearance 0)
			)
			(min_thickness 0.25)
			(keepout
				(tracks not_allowed)
				(vias allowed)
				(pads allowed)
				(copperpour not_allowed)
				(footprints allowed)
			)
			(placement
				(enabled no)
				(sheetname "")
			)
			(fill
				(thermal_gap 0.5)
				(thermal_bridge_width 0.5)
				(island_removal_mode 0)
			)
			(polygon
				(pts
					(arc
						(start 404.763224 9.419844)
						(mid 402.909024 9.419844)
						(end 404.763224 9.419844)
					)
				)
			)
		)
		(zone
			(layers "F.Cu" "B.Cu" "In1.Cu" "In2.Cu" "In3.Cu" "In4.Cu" "In5.Cu" "In6.Cu"
				"In7.Cu" "In8.Cu" "In9.Cu" "In10.Cu" "In11.Cu" "In12.Cu" "In13.Cu" "In14.Cu"
				"In15.Cu" "In16.Cu"
			)
			(hatch none 0.5)
			(connect_pads
				(clearance 0)
			)
			(min_thickness 0.25)
			(keepout
				(tracks not_allowed)
				(vias allowed)
				(pads allowed)
				(copperpour not_allowed)
				(footprints allowed)
			)
			(placement
				(enabled no)
				(sheetname "")
			)
			(fill
				(thermal_gap 0.5)
				(thermal_bridge_width 0.5)
				(island_removal_mode 0)
			)
			(polygon
				(pts
					(arc
						(start 404.763224 11.959844)
						(mid 402.909024 11.959844)
						(end 404.763224 11.959844)
					)
				)
			)
		)
		(zone
			(layer "B.Cu")
			(hatch none 0.5)
			(connect_pads
				(clearance 0)
			)
			(min_thickness 0.25)
			(keepout
				(tracks not_allowed)
				(vias allowed)
				(pads allowed)
				(copperpour not_allowed)
				(footprints allowed)
			)
			(placement
				(enabled no)
				(sheetname "")
			)
			(fill
				(thermal_gap 0.5)
				(thermal_bridge_width 0.5)
				(island_removal_mode 0)
			)
			(polygon
				(pts
					(xy 401.486624 11.238484) (xy 401.486624 11.14298) (xy 400.889724 11.14298) (xy 400.889724 10.73658)
					(xy 401.486624 10.73658) (xy 401.486624 10.643108) (xy 400.889724 10.643108) (xy 400.889724 10.236708)
					(xy 401.486624 10.236708) (xy 401.486624 10.141204) (xy 400.788124 10.141204) (xy 400.788124 11.238484)
				)
			)
		)
	)
	(footprint ""
		(layer "B.Cu")
		(at 408.899868 -301.599854 -90)
		(property "Reference" "C1990"
			(at 0 0 90)
			(layer "B.SilkS")
			(hide yes)
			(effects
				(font
					(size 1.27 1.27)
				)
				(justify mirror)
			)
		)
		(property "Value" ""
			(at 0 0 90)
			(layer "B.Fab")
			(effects
				(font
					(size 1.27 1.27)
				)
				(justify mirror)
			)
		)
		(duplicate_pad_numbers_are_jumpers no)
		(fp_line
			(start -0.299974 0.150114)
			(end 0.299974 0.150114)
			(stroke
				(width 0.1)
				(type default)
			)
			(layer "B.Fab")
		)
		(fp_line
			(start 0.299974 0.150114)
			(end 0.299974 -0.150114)
			(stroke
				(width 0.1)
				(type default)
			)
			(layer "B.Fab")
		)
		(fp_line
			(start -0.299974 -0.150114)
			(end -0.299974 0.150114)
			(stroke
				(width 0.1)
				(type default)
			)
			(layer "B.Fab")
		)
		(fp_line
			(start 0.299974 -0.150114)
			(end -0.299974 -0.150114)
			(stroke
				(width 0.1)
				(type default)
			)
			(layer "B.Fab")
		)
		(pad "1" smd rect
			(at 0.2667 0 90)
			(size 0.3048 0.381)
			(layers "B.Cu" "B.Mask" "B.Paste")
			(net "P0V8_SERDES_VDDA_PEX3")
		)
		(pad "2" smd rect
			(at -0.2667 0 90)
			(size 0.3048 0.381)
			(layers "B.Cu" "B.Mask" "B.Paste")
			(net "GND")
		)
	)
	(footprint ""
		(layer "B.Cu")
		(at 302.877474 -223.599502 90)
		(property "Reference" "R1862"
			(at 0 0 90)
			(layer "B.SilkS")
			(hide yes)
			(effects
				(font
					(size 1.27 1.27)
				)
				(justify mirror)
			)
		)
		(property "Value" ""
			(at 0 0 90)
			(layer "B.Fab")
			(effects
				(font
					(size 1.27 1.27)
				)
				(justify mirror)
			)
		)
		(duplicate_pad_numbers_are_jumpers no)
		(fp_line
			(start 0.7874 -0.4064)
			(end -0.7874 -0.4064)
			(stroke
				(width 0.1524)
				(type default)
			)
			(layer "B.SilkS")
		)
		(fp_line
			(start -0.7874 -0.4064)
			(end -0.7874 0.4064)
			(stroke
				(width 0.1524)
				(type default)
			)
			(layer "B.SilkS")
		)
		(fp_line
			(start 0.7874 0.4064)
			(end 0.7874 -0.4064)
			(stroke
				(width 0.1524)
				(type default)
			)
			(layer "B.SilkS")
		)
		(fp_line
			(start -0.7874 0.4064)
			(end 0.7874 0.4064)
			(stroke
				(width 0.1524)
				(type default)
			)
			(layer "B.SilkS")
		)
		(fp_line
			(start 0.67945 -0.305054)
			(end 0.12065 -0.305054)
			(stroke
				(width 0.1)
				(type default)
			)
			(layer "B.Fab")
		)
		(fp_line
			(start 0.12065 -0.305054)
			(end 0.12065 -0.2794)
			(stroke
				(width 0.1)
				(type default)
			)
			(layer "B.Fab")
		)
		(fp_line
			(start -0.12065 -0.3048)
			(end -0.67945 -0.3048)
			(stroke
				(width 0.1)
				(type default)
			)
			(layer "B.Fab")
		)
		(fp_line
			(start -0.67945 -0.3048)
			(end -0.67945 0.3048)
			(stroke
				(width 0.1)
				(type default)
			)
			(layer "B.Fab")
		)
		(fp_line
			(start 0.12065 -0.2794)
			(end -0.12065 -0.2794)
			(stroke
				(width 0.1)
				(type default)
			)
			(layer "B.Fab")
		)
		(fp_line
			(start -0.12065 -0.2794)
			(end -0.12065 -0.3048)
			(stroke
				(width 0.1)
				(type default)
			)
			(layer "B.Fab")
		)
		(fp_line
			(start 0.12065 0.2794)
			(end 0.12065 0.3048)
			(stroke
				(width 0.1)
				(type default)
			)
			(layer "B.Fab")
		)
		(fp_line
			(start -0.120396 0.2794)
			(end 0.12065 0.2794)
			(stroke
				(width 0.1)
				(type default)
			)
			(layer "B.Fab")
		)
		(fp_line
			(start 0.67945 0.3048)
			(end 0.67945 -0.305054)
			(stroke
				(width 0.1)
				(type default)
			)
			(layer "B.Fab")
		)
		(fp_line
			(start 0.12065 0.3048)
			(end 0.67945 0.3048)
			(stroke
				(width 0.1)
				(type default)
			)
			(layer "B.Fab")
		)
		(fp_line
			(start -0.120396 0.3048)
			(end -0.120396 0.2794)
			(stroke
				(width 0.1)
				(type default)
			)
			(layer "B.Fab")
		)
		(fp_line
			(start -0.67945 0.3048)
			(end -0.120396 0.3048)
			(stroke
				(width 0.1)
				(type default)
			)
			(layer "B.Fab")
		)
		(pad "1" smd circle
			(at 0.40005 0 270)
			(size 0 0)
			(layers "B.Cu" "B.Mask" "B.Paste")
			(net "P3V3_AUX")
		)
		(pad "2" smd circle
			(at -0.40005 0 270)
			(size 0 0)
			(layers "B.Cu" "B.Mask" "B.Paste")
			(net "RST_GPU_PERST_1_BUF_N")
		)
	)
	(footprint ""
		(layer "B.Cu")
		(at 387.35 -227.203 90)
		(property "Reference" "R927"
			(at 0 0 90)
			(layer "B.SilkS")
			(hide yes)
			(effects
				(font
					(size 1.27 1.27)
				)
				(justify mirror)
			)
		)
		(property "Value" ""
			(at 0 0 90)
			(layer "B.Fab")
			(effects
				(font
					(size 1.27 1.27)
				)
				(justify mirror)
			)
		)
		(duplicate_pad_numbers_are_jumpers no)
		(fp_line
			(start 0.7874 -0.4064)
			(end -0.7874 -0.4064)
			(stroke
				(width 0.1524)
				(type default)
			)
			(layer "B.SilkS")
		)
		(fp_line
			(start -0.7874 -0.4064)
			(end -0.7874 0.4064)
			(stroke
				(width 0.1524)
				(type default)
			)
			(layer "B.SilkS")
		)
		(fp_line
			(start 0.7874 0.4064)
			(end 0.7874 -0.4064)
			(stroke
				(width 0.1524)
				(type default)
			)
			(layer "B.SilkS")
		)
		(fp_line
			(start -0.7874 0.4064)
			(end 0.7874 0.4064)
			(stroke
				(width 0.1524)
				(type default)
			)
			(layer "B.SilkS")
		)
		(fp_line
			(start 0.67945 -0.305054)
			(end 0.12065 -0.305054)
			(stroke
				(width 0.1)
				(type default)
			)
			(layer "B.Fab")
		)
		(fp_line
			(start 0.12065 -0.305054)
			(end 0.12065 -0.2794)
			(stroke
				(width 0.1)
				(type default)
			)
			(layer "B.Fab")
		)
		(fp_line
			(start -0.12065 -0.3048)
			(end -0.67945 -0.3048)
			(stroke
				(width 0.1)
				(type default)
			)
			(layer "B.Fab")
		)
		(fp_line
			(start -0.67945 -0.3048)
			(end -0.67945 0.3048)
			(stroke
				(width 0.1)
				(type default)
			)
			(layer "B.Fab")
		)
		(fp_line
			(start 0.12065 -0.2794)
			(end -0.12065 -0.2794)
			(stroke
				(width 0.1)
				(type default)
			)
			(layer "B.Fab")
		)
		(fp_line
			(start -0.12065 -0.2794)
			(end -0.12065 -0.3048)
			(stroke
				(width 0.1)
				(type default)
			)
			(layer "B.Fab")
		)
		(fp_line
			(start 0.12065 0.2794)
			(end 0.12065 0.3048)
			(stroke
				(width 0.1)
				(type default)
			)
			(layer "B.Fab")
		)
		(fp_line
			(start -0.120396 0.2794)
			(end 0.12065 0.2794)
			(stroke
				(width 0.1)
				(type default)
			)
			(layer "B.Fab")
		)
		(fp_line
			(start 0.67945 0.3048)
			(end 0.67945 -0.305054)
			(stroke
				(width 0.1)
				(type default)
			)
			(layer "B.Fab")
		)
		(fp_line
			(start 0.12065 0.3048)
			(end 0.67945 0.3048)
			(stroke
				(width 0.1)
				(type default)
			)
			(layer "B.Fab")
		)
		(fp_line
			(start -0.120396 0.3048)
			(end -0.120396 0.2794)
			(stroke
				(width 0.1)
				(type default)
			)
			(layer "B.Fab")
		)
		(fp_line
			(start -0.67945 0.3048)
			(end -0.120396 0.3048)
			(stroke
				(width 0.1)
				(type default)
			)
			(layer "B.Fab")
		)
		(pad "1" smd circle
			(at 0.40005 0 270)
			(size 0 0)
			(layers "B.Cu" "B.Mask" "B.Paste")
			(net "UART_PEX0_SDB_RX")
		)
		(pad "2" smd circle
			(at -0.40005 0 270)
			(size 0 0)
			(layers "B.Cu" "B.Mask" "B.Paste")
			(net "UART_PEX0_SDB_R_RX")
		)
	)
	(footprint ""
		(layer "B.Cu")
		(at 346.093288 -221.986856 -90)
		(property "Reference" "C2043"
			(at 0 0 90)
			(layer "B.SilkS")
			(hide yes)
			(effects
				(font
					(size 1.27 1.27)
				)
				(justify mirror)
			)
		)
		(property "Value" ""
			(at 0 0 90)
			(layer "B.Fab")
			(effects
				(font
					(size 1.27 1.27)
				)
				(justify mirror)
			)
		)
		(duplicate_pad_numbers_are_jumpers no)
		(fp_line
			(start -0.69215 0.2921)
			(end 0.69215 0.2921)
			(stroke
				(width 0.1524)
				(type default)
			)
			(layer "B.SilkS")
		)
		(fp_line
			(start 0.69215 0.2921)
			(end 0.69215 -0.2921)
			(stroke
				(width 0.1524)
				(type default)
			)
			(layer "B.SilkS")
		)
		(fp_line
			(start -0.69215 -0.2921)
			(end -0.69215 0.2921)
			(stroke
				(width 0.1524)
				(type default)
			)
			(layer "B.SilkS")
		)
		(fp_line
			(start 0.69215 -0.2921)
			(end -0.69215 -0.2921)
			(stroke
				(width 0.1524)
				(type default)
			)
			(layer "B.SilkS")
		)
		(fp_line
			(start -0.51435 0.2794)
			(end 0.51435 0.2794)
			(stroke
				(width 0.1)
				(type default)
			)
			(layer "B.Fab")
		)
		(fp_line
			(start 0.51435 0.2794)
			(end 0.51435 -0.2794)
			(stroke
				(width 0.1)
				(type default)
			)
			(layer "B.Fab")
		)
		(fp_line
			(start -0.51435 -0.2794)
			(end -0.51435 0.2794)
			(stroke
				(width 0.1)
				(type default)
			)
			(layer "B.Fab")
		)
		(fp_line
			(start 0.51435 -0.2794)
			(end -0.51435 -0.2794)
			(stroke
				(width 0.1)
				(type default)
			)
			(layer "B.Fab")
		)
		(pad "1" smd circle
			(at 0.40005 0 90)
			(size 0 0)
			(layers "B.Cu" "B.Mask" "B.Paste")
			(net "P3V3_FPGA_VCCIO1")
		)
		(pad "2" smd circle
			(at -0.40005 0 90)
			(size 0 0)
			(layers "B.Cu" "B.Mask" "B.Paste")
			(net "GND")
		)
		(zone
			(layer "B.Cu")
			(hatch none 0.5)
			(connect_pads
				(clearance 0)
			)
			(min_thickness 0.25)
			(keepout
				(tracks not_allowed)
				(vias allowed)
				(pads allowed)
				(copperpour not_allowed)
				(footprints allowed)
			)
			(placement
				(enabled no)
				(sheetname "")
			)
			(fill
				(thermal_gap 0.5)
				(thermal_bridge_width 0.5)
				(island_removal_mode 0)
			)
			(polygon
				(pts
					(xy 346.005658 -221.796356) (xy 345.947492 -221.887796) (xy 345.947492 -222.087186) (xy 346.005658 -222.177356)
					(xy 346.180918 -222.177356) (xy 346.239338 -222.087186) (xy 346.239338 -221.887796) (xy 346.181172 -221.796356)
				)
			)
		)
	)
	(footprint ""
		(layer "B.Cu")
		(at 237.62843 -349.473012 180)
		(property "Reference" "PR7149"
			(at 0 0 0)
			(layer "B.SilkS")
			(hide yes)
			(effects
				(font
					(size 1.27 1.27)
				)
				(justify mirror)
			)
		)
		(property "Value" ""
			(at 0 0 0)
			(layer "B.Fab")
			(effects
				(font
					(size 1.27 1.27)
				)
				(justify mirror)
			)
		)
		(duplicate_pad_numbers_are_jumpers no)
		(fp_line
			(start 0.7874 0.4064)
			(end 0.7874 -0.4064)
			(stroke
				(width 0.1524)
				(type default)
			)
			(layer "B.SilkS")
		)
		(fp_line
			(start 0.7874 -0.4064)
			(end -0.7874 -0.4064)
			(stroke
				(width 0.1524)
				(type default)
			)
			(layer "B.SilkS")
		)
		(fp_line
			(start -0.7874 0.4064)
			(end 0.7874 0.4064)
			(stroke
				(width 0.1524)
				(type default)
			)
			(layer "B.SilkS")
		)
		(fp_line
			(start -0.7874 -0.4064)
			(end -0.7874 0.4064)
			(stroke
				(width 0.1524)
				(type default)
			)
			(layer "B.SilkS")
		)
		(fp_line
			(start 0.67945 0.3048)
			(end 0.67945 -0.305054)
			(stroke
				(width 0.1)
				(type default)
			)
			(layer "B.Fab")
		)
		(fp_line
			(start 0.67945 -0.305054)
			(end 0.12065 -0.305054)
			(stroke
				(width 0.1)
				(type default)
			)
			(layer "B.Fab")
		)
		(fp_line
			(start 0.12065 0.3048)
			(end 0.67945 0.3048)
			(stroke
				(width 0.1)
				(type default)
			)
			(layer "B.Fab")
		)
		(fp_line
			(start 0.12065 0.2794)
			(end 0.12065 0.3048)
			(stroke
				(width 0.1)
				(type default)
			)
			(layer "B.Fab")
		)
		(fp_line
			(start 0.12065 -0.2794)
			(end -0.12065 -0.2794)
			(stroke
				(width 0.1)
				(type default)
			)
			(layer "B.Fab")
		)
		(fp_line
			(start 0.12065 -0.305054)
			(end 0.12065 -0.2794)
			(stroke
				(width 0.1)
				(type default)
			)
			(layer "B.Fab")
		)
		(fp_line
			(start -0.120396 0.3048)
			(end -0.120396 0.2794)
			(stroke
				(width 0.1)
				(type default)
			)
			(layer "B.Fab")
		)
		(fp_line
			(start -0.120396 0.2794)
			(end 0.12065 0.2794)
			(stroke
				(width 0.1)
				(type default)
			)
			(layer "B.Fab")
		)
		(fp_line
			(start -0.12065 -0.2794)
			(end -0.12065 -0.3048)
			(stroke
				(width 0.1)
				(type default)
			)
			(layer "B.Fab")
		)
		(fp_line
			(start -0.12065 -0.3048)
			(end -0.67945 -0.3048)
			(stroke
				(width 0.1)
				(type default)
			)
			(layer "B.Fab")
		)
		(fp_line
			(start -0.67945 0.3048)
			(end -0.120396 0.3048)
			(stroke
				(width 0.1)
				(type default)
			)
			(layer "B.Fab")
		)
		(fp_line
			(start -0.67945 -0.3048)
			(end -0.67945 0.3048)
			(stroke
				(width 0.1)
				(type default)
			)
			(layer "B.Fab")
		)
		(pad "1" smd circle
			(at 0.40005 0)
			(size 0 0)
			(layers "B.Cu" "B.Mask" "B.Paste")
			(net "P12V_HSC_ADC_N")
		)
		(pad "2" smd circle
			(at -0.40005 0)
			(size 0 0)
			(layers "B.Cu" "B.Mask" "B.Paste")
			(net "P12V_HSC_SENSE1_N")
		)
	)
)
